(kicad_pcb
	(version 20260206)
	(generator "pcbnew")
	(generator_version "10.0")
	(general
		(thickness 1.6)
		(legacy_teardrops no)
	)
	(paper "A4")
	(title_block
		(title "01162023_DA0F0TEBIF0_F0T_Expander_BD_F_brd_V02_OCP.brd")
		(comment 1 "Grand Teton / footprints 898-903 of 9728")
	)
	(layers
		(0 "F.Cu" signal "TOP")
		(4 "In1.Cu" signal "GND")
		(6 "In2.Cu" signal "VCC")
		(8 "In3.Cu" signal "VCC1")
		(10 "In4.Cu" signal "GND1")
		(12 "In5.Cu" signal "IN1")
		(14 "In6.Cu" signal "GND2")
		(16 "In7.Cu" signal "IN2")
		(18 "In8.Cu" signal "GND3")
		(20 "In9.Cu" signal "IN3")
		(22 "In10.Cu" signal "GND4")
		(24 "In11.Cu" signal "IN4")
		(26 "In12.Cu" signal "GND5")
		(28 "In13.Cu" signal "IN5")
		(30 "In14.Cu" signal "GND6")
		(32 "In15.Cu" signal "IN6")
		(34 "In16.Cu" signal "GND7")
		(2 "B.Cu" signal "BOTTOM")
		(9 "F.Adhes" user "F.Adhesive")
		(11 "B.Adhes" user "B.Adhesive")
		(13 "F.Paste" user "Package Geometry/Pastemask Top")
		(15 "B.Paste" user "Package Geometry/Pastemask Bottom")
		(5 "F.SilkS" user "Ref Des/Silkscreen Top")
		(7 "B.SilkS" user "Ref Des/Silkscreen Bottom")
		(1 "F.Mask" user "Board Geometry/Soldermask Top")
		(3 "B.Mask" user "Board Geometry/Soldermask Bottom")
		(17 "Dwgs.User" user "User.Drawings")
		(19 "Cmts.User" user "User.Comments")
		(21 "Eco1.User" user "User.Eco1")
		(23 "Eco2.User" user "User.Eco2")
		(25 "Edge.Cuts" user "Board Geometry/Outline")
		(27 "Margin" user)
		(31 "F.CrtYd" user "Package Geometry/Place Bound Top")
		(29 "B.CrtYd" user "Package Geometry/Place Bound Bottom")
		(35 "F.Fab" user "Ref Des/Assembly Top")
		(33 "B.Fab" user "Ref Des/Assembly Bottom")
	)
	(footprint ""
		(layer "F.Cu")
		(at 447.312288 -405.070818 90)
		(property "Reference" "R5602"
			(at 0 0 90)
			(layer "F.SilkS")
			(hide yes)
			(effects
				(font
					(size 1.27 1.27)
				)
			)
		)
		(property "Value" ""
			(at 0 0 90)
			(layer "F.Fab")
			(effects
				(font
					(size 1.27 1.27)
				)
			)
		)
		(duplicate_pad_numbers_are_jumpers no)
		(fp_line
			(start 0.7874 -0.4064)
			(end 0.7874 0.4064)
			(stroke
				(width 0.1524)
				(type default)
			)
			(layer "F.SilkS")
		)
		(fp_line
			(start -0.7874 -0.4064)
			(end 0.7874 -0.4064)
			(stroke
				(width 0.1524)
				(type default)
			)
			(layer "F.SilkS")
		)
		(fp_line
			(start 0.7874 0.4064)
			(end -0.7874 0.4064)
			(stroke
				(width 0.1524)
				(type default)
			)
			(layer "F.SilkS")
		)
		(fp_line
			(start -0.7874 0.4064)
			(end -0.7874 -0.4064)
			(stroke
				(width 0.1524)
				(type default)
			)
			(layer "F.SilkS")
		)
		(fp_line
			(start -0.12065 -0.305054)
			(end -0.12065 -0.2794)
			(stroke
				(width 0.1)
				(type default)
			)
			(layer "F.Fab")
		)
		(fp_line
			(start -0.67945 -0.305054)
			(end -0.12065 -0.305054)
			(stroke
				(width 0.1)
				(type default)
			)
			(layer "F.Fab")
		)
		(fp_line
			(start 0.67945 -0.3048)
			(end 0.67945 0.3048)
			(stroke
				(width 0.1)
				(type default)
			)
			(layer "F.Fab")
		)
		(fp_line
			(start 0.12065 -0.3048)
			(end 0.67945 -0.3048)
			(stroke
				(width 0.1)
				(type default)
			)
			(layer "F.Fab")
		)
		(fp_line
			(start 0.12065 -0.2794)
			(end 0.12065 -0.3048)
			(stroke
				(width 0.1)
				(type default)
			)
			(layer "F.Fab")
		)
		(fp_line
			(start -0.12065 -0.2794)
			(end 0.12065 -0.2794)
			(stroke
				(width 0.1)
				(type default)
			)
			(layer "F.Fab")
		)
		(fp_line
			(start 0.120396 0.2794)
			(end -0.12065 0.2794)
			(stroke
				(width 0.1)
				(type default)
			)
			(layer "F.Fab")
		)
		(fp_line
			(start -0.12065 0.2794)
			(end -0.12065 0.3048)
			(stroke
				(width 0.1)
				(type default)
			)
			(layer "F.Fab")
		)
		(fp_line
			(start 0.67945 0.3048)
			(end 0.120396 0.3048)
			(stroke
				(width 0.1)
				(type default)
			)
			(layer "F.Fab")
		)
		(fp_line
			(start 0.120396 0.3048)
			(end 0.120396 0.2794)
			(stroke
				(width 0.1)
				(type default)
			)
			(layer "F.Fab")
		)
		(fp_line
			(start -0.12065 0.3048)
			(end -0.67945 0.3048)
			(stroke
				(width 0.1)
				(type default)
			)
			(layer "F.Fab")
		)
		(fp_line
			(start -0.67945 0.3048)
			(end -0.67945 -0.305054)
			(stroke
				(width 0.1)
				(type default)
			)
			(layer "F.Fab")
		)
		(pad "1" smd circle
			(at -0.40005 0 90)
			(size 0 0)
			(layers "F.Cu" "F.Mask" "F.Paste")
			(net "SMB_BIC_I2C6_MUX_THERMAL_R_SDA")
		)
		(pad "2" smd circle
			(at 0.40005 0 90)
			(size 0 0)
			(layers "F.Cu" "F.Mask" "F.Paste")
			(net "SMB_LM75_1_SDA")
		)
	)
	(footprint ""
		(layer "F.Cu")
		(at 378.852684 -91.1098 180)
		(property "Reference" "R1758"
			(at 0 0 180)
			(layer "F.SilkS")
			(hide yes)
			(effects
				(font
					(size 1.27 1.27)
				)
			)
		)
		(property "Value" ""
			(at 0 0 180)
			(layer "F.Fab")
			(effects
				(font
					(size 1.27 1.27)
				)
			)
		)
		(duplicate_pad_numbers_are_jumpers no)
		(fp_line
			(start 0.7874 0.4064)
			(end -0.7874 0.4064)
			(stroke
				(width 0.1524)
				(type default)
			)
			(layer "F.SilkS")
		)
		(fp_line
			(start 0.7874 -0.4064)
			(end 0.7874 0.4064)
			(stroke
				(width 0.1524)
				(type default)
			)
			(layer "F.SilkS")
		)
		(fp_line
			(start -0.7874 0.4064)
			(end -0.7874 -0.4064)
			(stroke
				(width 0.1524)
				(type default)
			)
			(layer "F.SilkS")
		)
		(fp_line
			(start -0.7874 -0.4064)
			(end 0.7874 -0.4064)
			(stroke
				(width 0.1524)
				(type default)
			)
			(layer "F.SilkS")
		)
		(fp_line
			(start 0.67945 0.3048)
			(end 0.120396 0.3048)
			(stroke
				(width 0.1)
				(type default)
			)
			(layer "F.Fab")
		)
		(fp_line
			(start 0.67945 -0.3048)
			(end 0.67945 0.3048)
			(stroke
				(width 0.1)
				(type default)
			)
			(layer "F.Fab")
		)
		(fp_line
			(start 0.12065 -0.2794)
			(end 0.12065 -0.3048)
			(stroke
				(width 0.1)
				(type default)
			)
			(layer "F.Fab")
		)
		(fp_line
			(start 0.12065 -0.3048)
			(end 0.67945 -0.3048)
			(stroke
				(width 0.1)
				(type default)
			)
			(layer "F.Fab")
		)
		(fp_line
			(start 0.120396 0.3048)
			(end 0.120396 0.2794)
			(stroke
				(width 0.1)
				(type default)
			)
			(layer "F.Fab")
		)
		(fp_line
			(start 0.120396 0.2794)
			(end -0.12065 0.2794)
			(stroke
				(width 0.1)
				(type default)
			)
			(layer "F.Fab")
		)
		(fp_line
			(start -0.12065 0.3048)
			(end -0.67945 0.3048)
			(stroke
				(width 0.1)
				(type default)
			)
			(layer "F.Fab")
		)
		(fp_line
			(start -0.12065 0.2794)
			(end -0.12065 0.3048)
			(stroke
				(width 0.1)
				(type default)
			)
			(layer "F.Fab")
		)
		(fp_line
			(start -0.12065 -0.2794)
			(end 0.12065 -0.2794)
			(stroke
				(width 0.1)
				(type default)
			)
			(layer "F.Fab")
		)
		(fp_line
			(start -0.12065 -0.305054)
			(end -0.12065 -0.2794)
			(stroke
				(width 0.1)
				(type default)
			)
			(layer "F.Fab")
		)
		(fp_line
			(start -0.67945 0.3048)
			(end -0.67945 -0.305054)
			(stroke
				(width 0.1)
				(type default)
			)
			(layer "F.Fab")
		)
		(fp_line
			(start -0.67945 -0.305054)
			(end -0.12065 -0.305054)
			(stroke
				(width 0.1)
				(type default)
			)
			(layer "F.Fab")
		)
		(pad "1" smd circle
			(at -0.40005 0 180)
			(size 0 0)
			(layers "F.Cu" "F.Mask" "F.Paste")
			(net "BIC_I2C6_MUX_A0")
		)
		(pad "2" smd circle
			(at 0.40005 0 180)
			(size 0 0)
			(layers "F.Cu" "F.Mask" "F.Paste")
			(net "GND")
		)
	)
	(footprint ""
		(layer "F.Cu")
		(at 155.682442 -252.356874 -90)
		(property "Reference" "R3961"
			(at 0 0 270)
			(layer "F.SilkS")
			(hide yes)
			(effects
				(font
					(size 1.27 1.27)
				)
			)
		)
		(property "Value" ""
			(at 0 0 270)
			(layer "F.Fab")
			(effects
				(font
					(size 1.27 1.27)
				)
			)
		)
		(duplicate_pad_numbers_are_jumpers no)
		(fp_line
			(start -0.7874 0.4064)
			(end -0.7874 -0.4064)
			(stroke
				(width 0.1524)
				(type default)
			)
			(layer "F.SilkS")
		)
		(fp_line
			(start 0.7874 0.4064)
			(end -0.7874 0.4064)
			(stroke
				(width 0.1524)
				(type default)
			)
			(layer "F.SilkS")
		)
		(fp_line
			(start -0.7874 -0.4064)
			(end 0.7874 -0.4064)
			(stroke
				(width 0.1524)
				(type default)
			)
			(layer "F.SilkS")
		)
		(fp_line
			(start 0.7874 -0.4064)
			(end 0.7874 0.4064)
			(stroke
				(width 0.1524)
				(type default)
			)
			(layer "F.SilkS")
		)
		(fp_line
			(start -0.67945 0.3048)
			(end -0.67945 -0.305054)
			(stroke
				(width 0.1)
				(type default)
			)
			(layer "F.Fab")
		)
		(fp_line
			(start -0.12065 0.3048)
			(end -0.67945 0.3048)
			(stroke
				(width 0.1)
				(type default)
			)
			(layer "F.Fab")
		)
		(fp_line
			(start 0.120396 0.3048)
			(end 0.120396 0.2794)
			(stroke
				(width 0.1)
				(type default)
			)
			(layer "F.Fab")
		)
		(fp_line
			(start 0.67945 0.3048)
			(end 0.120396 0.3048)
			(stroke
				(width 0.1)
				(type default)
			)
			(layer "F.Fab")
		)
		(fp_line
			(start -0.12065 0.2794)
			(end -0.12065 0.3048)
			(stroke
				(width 0.1)
				(type default)
			)
			(layer "F.Fab")
		)
		(fp_line
			(start 0.120396 0.2794)
			(end -0.12065 0.2794)
			(stroke
				(width 0.1)
				(type default)
			)
			(layer "F.Fab")
		)
		(fp_line
			(start -0.12065 -0.2794)
			(end 0.12065 -0.2794)
			(stroke
				(width 0.1)
				(type default)
			)
			(layer "F.Fab")
		)
		(fp_line
			(start 0.12065 -0.2794)
			(end 0.12065 -0.3048)
			(stroke
				(width 0.1)
				(type default)
			)
			(layer "F.Fab")
		)
		(fp_line
			(start 0.12065 -0.3048)
			(end 0.67945 -0.3048)
			(stroke
				(width 0.1)
				(type default)
			)
			(layer "F.Fab")
		)
		(fp_line
			(start 0.67945 -0.3048)
			(end 0.67945 0.3048)
			(stroke
				(width 0.1)
				(type default)
			)
			(layer "F.Fab")
		)
		(fp_line
			(start -0.67945 -0.305054)
			(end -0.12065 -0.305054)
			(stroke
				(width 0.1)
				(type default)
			)
			(layer "F.Fab")
		)
		(fp_line
			(start -0.12065 -0.305054)
			(end -0.12065 -0.2794)
			(stroke
				(width 0.1)
				(type default)
			)
			(layer "F.Fab")
		)
		(pad "1" smd circle
			(at -0.40005 0 270)
			(size 0 0)
			(layers "F.Cu" "F.Mask" "F.Paste")
			(net "PEX1_PCA9555_INT_R_N")
		)
		(pad "2" smd circle
			(at 0.40005 0 270)
			(size 0 0)
			(layers "F.Cu" "F.Mask" "F.Paste")
			(net "P1V8_PEX")
		)
	)
	(footprint ""
		(layer "F.Cu")
		(at 320.675508 -122.931682 -90)
		(property "Reference" "PD55"
			(at 4.110482 2.107438 90)
			(unlocked yes)
			(layer "F.SilkS")
			(effects
				(font
					(size 0.7874 0.5842)
					(thickness 0.1524)
				)
				(justify left)
			)
		)
		(property "Value" ""
			(at 0 0 270)
			(layer "F.Fab")
			(effects
				(font
					(size 1.27 1.27)
				)
			)
		)
		(duplicate_pad_numbers_are_jumpers no)
		(fp_line
			(start -3.400044 1.459992)
			(end -3.400044 -1.459992)
			(stroke
				(width 0.1524)
				(type default)
			)
			(layer "F.SilkS")
		)
		(fp_line
			(start 4.107942 1.459992)
			(end -3.400044 1.459992)
			(stroke
				(width 0.1524)
				(type default)
			)
			(layer "F.SilkS")
		)
		(fp_line
			(start -3.400044 -1.459992)
			(end 4.107942 -1.459992)
			(stroke
				(width 0.1524)
				(type default)
			)
			(layer "F.SilkS")
		)
		(fp_line
			(start 4.107942 -1.459992)
			(end 4.107942 1.459992)
			(stroke
				(width 0.1524)
				(type default)
			)
			(layer "F.SilkS")
		)
		(fp_rect
			(start 4.107942 1.459992)
			(end 3.308096 -1.459992)
			(stroke
				(width 0)
				(type default)
			)
			(fill yes)
			(layer "F.SilkS")
		)
		(fp_line
			(start -2.29997 1.459992)
			(end -2.29997 -1.459992)
			(stroke
				(width 0.1)
				(type default)
			)
			(layer "F.Fab")
		)
		(fp_line
			(start 2.29997 1.459992)
			(end -2.29997 1.459992)
			(stroke
				(width 0.1)
				(type default)
			)
			(layer "F.Fab")
		)
		(fp_line
			(start -2.29997 -1.459992)
			(end 2.29997 -1.459992)
			(stroke
				(width 0.1)
				(type default)
			)
			(layer "F.Fab")
		)
		(fp_line
			(start 2.29997 -1.459992)
			(end 2.29997 1.459992)
			(stroke
				(width 0.1)
				(type default)
			)
			(layer "F.Fab")
		)
		(fp_text user "-"
			(at 5.4102 0.29845 90)
			(unlocked yes)
			(layer "F.SilkS")
			(effects
				(font
					(size 1.905 1.4224)
					(thickness 0.1524)
				)
				(justify left)
			)
		)
		(fp_text user "+"
			(at -4.7752 -0.12065 270)
			(unlocked yes)
			(layer "F.SilkS")
			(effects
				(font
					(size 1.905 1.4224)
					(thickness 0.1524)
				)
				(justify left)
			)
		)
		(fp_text user "-"
			(at 5.4102 0.29845 90)
			(unlocked yes)
			(layer "F.Fab")
			(effects
				(font
					(size 1.905 1.4224)
					(thickness 0.1524)
				)
				(justify left)
			)
		)
		(fp_text user "+"
			(at -4.7752 -0.12065 270)
			(unlocked yes)
			(layer "F.Fab")
			(effects
				(font
					(size 1.905 1.4224)
					(thickness 0.1524)
				)
				(justify left)
			)
		)
		(pad "A" smd rect
			(at -1.999996 0)
			(size 1.7018 2.5146)
			(layers "F.Cu" "F.Mask" "F.Paste")
			(net "GND")
		)
		(pad "C" smd rect
			(at 1.999996 0)
			(size 1.7018 2.5146)
			(layers "F.Cu" "F.Mask" "F.Paste")
			(net "P3V3_NIC5")
		)
	)
	(footprint ""
		(layer "F.Cu")
		(at 359.859326 -259.1435 180)
		(property "Reference" "PR7170"
			(at 0 0 180)
			(layer "F.SilkS")
			(hide yes)
			(effects
				(font
					(size 1.27 1.27)
				)
			)
		)
		(property "Value" ""
			(at 0 0 180)
			(layer "F.Fab")
			(effects
				(font
					(size 1.27 1.27)
				)
			)
		)
		(duplicate_pad_numbers_are_jumpers no)
		(fp_line
			(start 0.7874 0.4064)
			(end -0.7874 0.4064)
			(stroke
				(width 0.1524)
				(type default)
			)
			(layer "F.SilkS")
		)
		(fp_line
			(start 0.7874 -0.4064)
			(end 0.7874 0.4064)
			(stroke
				(width 0.1524)
				(type default)
			)
			(layer "F.SilkS")
		)
		(fp_line
			(start -0.7874 0.4064)
			(end -0.7874 -0.4064)
			(stroke
				(width 0.1524)
				(type default)
			)
			(layer "F.SilkS")
		)
		(fp_line
			(start -0.7874 -0.4064)
			(end 0.7874 -0.4064)
			(stroke
				(width 0.1524)
				(type default)
			)
			(layer "F.SilkS")
		)
		(fp_line
			(start 0.67945 0.3048)
			(end 0.120396 0.3048)
			(stroke
				(width 0.1)
				(type default)
			)
			(layer "F.Fab")
		)
		(fp_line
			(start 0.67945 -0.3048)
			(end 0.67945 0.3048)
			(stroke
				(width 0.1)
				(type default)
			)
			(layer "F.Fab")
		)
		(fp_line
			(start 0.12065 -0.2794)
			(end 0.12065 -0.3048)
			(stroke
				(width 0.1)
				(type default)
			)
			(layer "F.Fab")
		)
		(fp_line
			(start 0.12065 -0.3048)
			(end 0.67945 -0.3048)
			(stroke
				(width 0.1)
				(type default)
			)
			(layer "F.Fab")
		)
		(fp_line
			(start 0.120396 0.3048)
			(end 0.120396 0.2794)
			(stroke
				(width 0.1)
				(type default)
			)
			(layer "F.Fab")
		)
		(fp_line
			(start 0.120396 0.2794)
			(end -0.12065 0.2794)
			(stroke
				(width 0.1)
				(type default)
			)
			(layer "F.Fab")
		)
		(fp_line
			(start -0.12065 0.3048)
			(end -0.67945 0.3048)
			(stroke
				(width 0.1)
				(type default)
			)
			(layer "F.Fab")
		)
		(fp_line
			(start -0.12065 0.2794)
			(end -0.12065 0.3048)
			(stroke
				(width 0.1)
				(type default)
			)
			(layer "F.Fab")
		)
		(fp_line
			(start -0.12065 -0.2794)
			(end 0.12065 -0.2794)
			(stroke
				(width 0.1)
				(type default)
			)
			(layer "F.Fab")
		)
		(fp_line
			(start -0.12065 -0.305054)
			(end -0.12065 -0.2794)
			(stroke
				(width 0.1)
				(type default)
			)
			(layer "F.Fab")
		)
		(fp_line
			(start -0.67945 0.3048)
			(end -0.67945 -0.305054)
			(stroke
				(width 0.1)
				(type default)
			)
			(layer "F.Fab")
		)
		(fp_line
			(start -0.67945 -0.305054)
			(end -0.12065 -0.305054)
			(stroke
				(width 0.1)
				(type default)
			)
			(layer "F.Fab")
		)
		(pad "1" smd circle
			(at -0.40005 0 180)
			(size 0 0)
			(layers "F.Cu" "F.Mask" "F.Paste")
			(net "GND")
		)
		(pad "2" smd circle
			(at 0.40005 0 180)
			(size 0 0)
			(layers "F.Cu" "F.Mask" "F.Paste")
			(net "NC_P0V8_PEX2_SVID_ALERT_N_R")
		)
	)
	(footprint ""
		(layer "F.Cu")
		(at 91.379294 -300.641004 -90)
		(property "Reference" "R3881"
			(at 0 0 270)
			(layer "F.SilkS")
			(hide yes)
			(effects
				(font
					(size 1.27 1.27)
				)
			)
		)
		(property "Value" ""
			(at 0 0 270)
			(layer "F.Fab")
			(effects
				(font
					(size 1.27 1.27)
				)
			)
		)
		(duplicate_pad_numbers_are_jumpers no)
		(fp_line
			(start -0.7874 0.4064)
			(end -0.7874 -0.4064)
			(stroke
				(width 0.1524)
				(type default)
			)
			(layer "F.SilkS")
		)
		(fp_line
			(start 0.7874 0.4064)
			(end -0.7874 0.4064)
			(stroke
				(width 0.1524)
				(type default)
			)
			(layer "F.SilkS")
		)
		(fp_line
			(start -0.7874 -0.4064)
			(end 0.7874 -0.4064)
			(stroke
				(width 0.1524)
				(type default)
			)
			(layer "F.SilkS")
		)
		(fp_line
			(start 0.7874 -0.4064)
			(end 0.7874 0.4064)
			(stroke
				(width 0.1524)
				(type default)
			)
			(layer "F.SilkS")
		)
		(fp_line
			(start -0.67945 0.3048)
			(end -0.67945 -0.305054)
			(stroke
				(width 0.1)
				(type default)
			)
			(layer "F.Fab")
		)
		(fp_line
			(start -0.12065 0.3048)
			(end -0.67945 0.3048)
			(stroke
				(width 0.1)
				(type default)
			)
			(layer "F.Fab")
		)
		(fp_line
			(start 0.120396 0.3048)
			(end 0.120396 0.2794)
			(stroke
				(width 0.1)
				(type default)
			)
			(layer "F.Fab")
		)
		(fp_line
			(start 0.67945 0.3048)
			(end 0.120396 0.3048)
			(stroke
				(width 0.1)
				(type default)
			)
			(layer "F.Fab")
		)
		(fp_line
			(start -0.12065 0.2794)
			(end -0.12065 0.3048)
			(stroke
				(width 0.1)
				(type default)
			)
			(layer "F.Fab")
		)
		(fp_line
			(start 0.120396 0.2794)
			(end -0.12065 0.2794)
			(stroke
				(width 0.1)
				(type default)
			)
			(layer "F.Fab")
		)
		(fp_line
			(start -0.12065 -0.2794)
			(end 0.12065 -0.2794)
			(stroke
				(width 0.1)
				(type default)
			)
			(layer "F.Fab")
		)
		(fp_line
			(start 0.12065 -0.2794)
			(end 0.12065 -0.3048)
			(stroke
				(width 0.1)
				(type default)
			)
			(layer "F.Fab")
		)
		(fp_line
			(start 0.12065 -0.3048)
			(end 0.67945 -0.3048)
			(stroke
				(width 0.1)
				(type default)
			)
			(layer "F.Fab")
		)
		(fp_line
			(start 0.67945 -0.3048)
			(end 0.67945 0.3048)
			(stroke
				(width 0.1)
				(type default)
			)
			(layer "F.Fab")
		)
		(fp_line
			(start -0.67945 -0.305054)
			(end -0.12065 -0.305054)
			(stroke
				(width 0.1)
				(type default)
			)
			(layer "F.Fab")
		)
		(fp_line
			(start -0.12065 -0.305054)
			(end -0.12065 -0.2794)
			(stroke
				(width 0.1)
				(type default)
			)
			(layer "F.Fab")
		)
		(pad "1" smd circle
			(at -0.40005 0 270)
			(size 0 0)
			(layers "F.Cu" "F.Mask" "F.Paste")
			(net "I2C0_PEX0_SCL")
		)
		(pad "2" smd circle
			(at 0.40005 0 270)
			(size 0 0)
			(layers "F.Cu" "F.Mask" "F.Paste")
			(net "I2C_PEX0_HOST_SCL")
		)
	)
)
